# S9S_MB_2U (Grand Teton) — schematic netlist excerpt (pin names and nets, part order shuffled) for the footprints in the layout excerpt that follows; sources: Cadence DE-HDL packaged netlist, KiCad conversion of 03242023_DA0F0TMBIJ0_F0T_Motherboard_J_brd_V01_OCP.brd

PR4257  Q_RES  0 5% CHIP  pkg 0402LF  page 296 : A = NC_PVCCD_HV_CPU1_ACSP8 ; B = GND
R1236  Q_RES  240 1% EMPTY  pkg 0402LF  page 119 : A = GND ; B = PUD_XTAL_CPU1_MODE1

(kicad_pcb
	(version 20260206)
	(generator "pcbnew")
	(generator_version "10.0")
	(general
		(thickness 1.6)
		(legacy_teardrops no)
	)
	(paper "A4")
	(title_block
		(title "03242023_DA0F0TMBIJ0_F0T_Motherboard_J_brd_V01_OCP.brd")
		(comment 1 "Grand Teton / footprints 5699-5700 of 6105")
	)
	(layers
		(0 "F.Cu" signal "TOP")
		(4 "In1.Cu" signal "GND")
		(6 "In2.Cu" signal "IN1")
		(8 "In3.Cu" signal "GND1")
		(10 "In4.Cu" signal "IN2")
		(12 "In5.Cu" signal "GND2")
		(14 "In6.Cu" signal "IN3")
		(16 "In7.Cu" signal "GND3")
		(18 "In8.Cu" signal "VCC")
		(20 "In9.Cu" signal "VCC1")
		(22 "In10.Cu" signal "GND4")
		(24 "In11.Cu" signal "IN4")
		(26 "In12.Cu" signal "GND5")
		(28 "In13.Cu" signal "IN5")
		(30 "In14.Cu" signal "GND6")
		(32 "In15.Cu" signal "IN6")
		(34 "In16.Cu" signal "GND7")
		(2 "B.Cu" signal "BOTTOM")
		(9 "F.Adhes" user "F.Adhesive")
		(11 "B.Adhes" user "B.Adhesive")
		(13 "F.Paste" user "Package Geometry/Pastemask Top")
		(15 "B.Paste" user "Package Geometry/Pastemask Bottom")
		(5 "F.SilkS" user "Ref Des/Silkscreen Top")
		(7 "B.SilkS" user "Ref Des/Silkscreen Bottom")
		(1 "F.Mask" user "Board Geometry/Soldermask Top")
		(3 "B.Mask" user "Board Geometry/Soldermask Bottom")
		(17 "Dwgs.User" user "User.Drawings")
		(19 "Cmts.User" user "User.Comments")
		(21 "Eco1.User" user "User.Eco1")
		(23 "Eco2.User" user "User.Eco2")
		(25 "Edge.Cuts" user "Board Geometry/Outline")
		(27 "Margin" user)
		(31 "F.CrtYd" user "Package Geometry/Place Bound Top")
		(29 "B.CrtYd" user "Package Geometry/Place Bound Bottom")
		(35 "F.Fab" user "Ref Des/Assembly Top")
		(33 "B.Fab" user "Ref Des/Assembly Bottom")
	)
	(footprint ""
		(layer "B.Cu")
		(at 166.386002 -250.271534 180)
		(property "Reference" "R1236"
			(at 0 0 0)
			(layer "B.SilkS")
			(hide yes)
			(effects
				(font
					(size 1.27 1.27)
				)
				(justify mirror)
			)
		)
		(property "Value" ""
			(at 0 0 0)
			(layer "B.Fab")
			(effects
				(font
					(size 1.27 1.27)
				)
				(justify mirror)
			)
		)
		(duplicate_pad_numbers_are_jumpers no)
		(fp_line
			(start 0.7874 0.4064)
			(end 0.7874 -0.4064)
			(stroke
				(width 0.1524)
				(type default)
			)
			(layer "B.SilkS")
		)
		(fp_line
			(start 0.7874 -0.4064)
			(end -0.7874 -0.4064)
			(stroke
				(width 0.1524)
				(type default)
			)
			(layer "B.SilkS")
		)
		(fp_line
			(start -0.7874 0.4064)
			(end 0.7874 0.4064)
			(stroke
				(width 0.1524)
				(type default)
			)
			(layer "B.SilkS")
		)
		(fp_line
			(start -0.7874 -0.4064)
			(end -0.7874 0.4064)
			(stroke
				(width 0.1524)
				(type default)
			)
			(layer "B.SilkS")
		)
		(fp_line
			(start 0.67945 0.3048)
			(end 0.67945 -0.305054)
			(stroke
				(width 0.1)
				(type default)
			)
			(layer "B.Fab")
		)
		(fp_line
			(start 0.67945 -0.305054)
			(end 0.12065 -0.305054)
			(stroke
				(width 0.1)
				(type default)
			)
			(layer "B.Fab")
		)
		(fp_line
			(start 0.12065 0.3048)
			(end 0.67945 0.3048)
			(stroke
				(width 0.1)
				(type default)
			)
			(layer "B.Fab")
		)
		(fp_line
			(start 0.12065 0.2794)
			(end 0.12065 0.3048)
			(stroke
				(width 0.1)
				(type default)
			)
			(layer "B.Fab")
		)
		(fp_line
			(start 0.12065 -0.2794)
			(end -0.12065 -0.2794)
			(stroke
				(width 0.1)
				(type default)
			)
			(layer "B.Fab")
		)
		(fp_line
			(start 0.12065 -0.305054)
			(end 0.12065 -0.2794)
			(stroke
				(width 0.1)
				(type default)
			)
			(layer "B.Fab")
		)
		(fp_line
			(start -0.120396 0.3048)
			(end -0.120396 0.2794)
			(stroke
				(width 0.1)
				(type default)
			)
			(layer "B.Fab")
		)
		(fp_line
			(start -0.120396 0.2794)
			(end 0.12065 0.2794)
			(stroke
				(width 0.1)
				(type default)
			)
			(layer "B.Fab")
		)
		(fp_line
			(start -0.12065 -0.2794)
			(end -0.12065 -0.3048)
			(stroke
				(width 0.1)
				(type default)
			)
			(layer "B.Fab")
		)
		(fp_line
			(start -0.12065 -0.3048)
			(end -0.67945 -0.3048)
			(stroke
				(width 0.1)
				(type default)
			)
			(layer "B.Fab")
		)
		(fp_line
			(start -0.67945 0.3048)
			(end -0.120396 0.3048)
			(stroke
				(width 0.1)
				(type default)
			)
			(layer "B.Fab")
		)
		(fp_line
			(start -0.67945 -0.3048)
			(end -0.67945 0.3048)
			(stroke
				(width 0.1)
				(type default)
			)
			(layer "B.Fab")
		)
		(pad "1" smd circle
			(at 0.40005 0)
			(size 0 0)
			(layers "B.Cu" "B.Mask" "B.Paste")
			(net "GND")
		)
		(pad "2" smd circle
			(at -0.40005 0)
			(size 0 0)
			(layers "B.Cu" "B.Mask" "B.Paste")
			(net "PUD_XTAL_CPU1_MODE1")
		)
	)
	(footprint ""
		(layer "B.Cu")
		(at 30.226 -163.261548)
		(property "Reference" "PR4257"
			(at 0 0 0)
			(layer "B.SilkS")
			(hide yes)
			(effects
				(font
					(size 1.27 1.27)
				)
				(justify mirror)
			)
		)
		(property "Value" ""
			(at 0 0 0)
			(layer "B.Fab")
			(effects
				(font
					(size 1.27 1.27)
				)
				(justify mirror)
			)
		)
		(duplicate_pad_numbers_are_jumpers no)
		(fp_line
			(start -0.7874 -0.4064)
			(end -0.7874 0.4064)
			(stroke
				(width 0.1524)
				(type default)
			)
			(layer "B.SilkS")
		)
		(fp_line
			(start -0.7874 0.4064)
			(end 0.7874 0.4064)
			(stroke
				(width 0.1524)
				(type default)
			)
			(layer "B.SilkS")
		)
		(fp_line
			(start 0.7874 -0.4064)
			(end -0.7874 -0.4064)
			(stroke
				(width 0.1524)
				(type default)
			)
			(layer "B.SilkS")
		)
		(fp_line
			(start 0.7874 0.4064)
			(end 0.7874 -0.4064)
			(stroke
				(width 0.1524)
				(type default)
			)
			(layer "B.SilkS")
		)
		(fp_line
			(start -0.67945 -0.3048)
			(end -0.67945 0.3048)
			(stroke
				(width 0.1)
				(type default)
			)
			(layer "B.Fab")
		)
		(fp_line
			(start -0.67945 0.3048)
			(end -0.120396 0.3048)
			(stroke
				(width 0.1)
				(type default)
			)
			(layer "B.Fab")
		)
		(fp_line
			(start -0.12065 -0.3048)
			(end -0.67945 -0.3048)
			(stroke
				(width 0.1)
				(type default)
			)
			(layer "B.Fab")
		)
		(fp_line
			(start -0.12065 -0.2794)
			(end -0.12065 -0.3048)
			(stroke
				(width 0.1)
				(type default)
			)
			(layer "B.Fab")
		)
		(fp_line
			(start -0.120396 0.2794)
			(end 0.12065 0.2794)
			(stroke
				(width 0.1)
				(type default)
			)
			(layer "B.Fab")
		)
		(fp_line
			(start -0.120396 0.3048)
			(end -0.120396 0.2794)
			(stroke
				(width 0.1)
				(type default)
			)
			(layer "B.Fab")
		)
		(fp_line
			(start 0.12065 -0.305054)
			(end 0.12065 -0.2794)
			(stroke
				(width 0.1)
				(type default)
			)
			(layer "B.Fab")
		)
		(fp_line
			(start 0.12065 -0.2794)
			(end -0.12065 -0.2794)
			(stroke
				(width 0.1)
				(type default)
			)
			(layer "B.Fab")
		)
		(fp_line
			(start 0.12065 0.2794)
			(end 0.12065 0.3048)
			(stroke
				(width 0.1)
				(type default)
			)
			(layer "B.Fab")
		)
		(fp_line
			(start 0.12065 0.3048)
			(end 0.67945 0.3048)
			(stroke
				(width 0.1)
				(type default)
			)
			(layer "B.Fab")
		)
		(fp_line
			(start 0.67945 -0.305054)
			(end 0.12065 -0.305054)
			(stroke
				(width 0.1)
				(type default)
			)
			(layer "B.Fab")
		)
		(fp_line
			(start 0.67945 0.3048)
			(end 0.67945 -0.305054)
			(stroke
				(width 0.1)
				(type default)
			)
			(layer "B.Fab")
		)
		(pad "1" smd circle
			(at 0.40005 0 180)
			(size 0 0)
			(layers "B.Cu" "B.Mask" "B.Paste")
			(net "NC_PVCCD_HV_CPU1_ACSP8")
		)
		(pad "2" smd circle
			(at -0.40005 0 180)
			(size 0 0)
			(layers "B.Cu" "B.Mask" "B.Paste")
			(net "GND")
		)
	)
)
